(kicad_pcb
	(version 20260206)
	(generator "pcbnew")
	(generator_version "10.0")
	(general
		(thickness 1.6)
		(legacy_teardrops no)
	)
	(paper "A4")
	(title_block
		(title "9052_F0T_PDB_Converter_Brick_F_V03_1208_1600_OCP.brd")
		(comment 1 "Grand Teton / footprints 559-564 of 578")
	)
	(layers
		(0 "F.Cu" signal "TOP")
		(4 "In1.Cu" signal "GND")
		(6 "In2.Cu" signal "IN1")
		(8 "In3.Cu" signal "GND1")
		(10 "In4.Cu" signal "VCC")
		(12 "In5.Cu" signal "VCC1")
		(14 "In6.Cu" signal "GND2")
		(16 "In7.Cu" signal "IN2")
		(18 "In8.Cu" signal "GND3")
		(2 "B.Cu" signal "BOTTOM")
		(9 "F.Adhes" user "F.Adhesive")
		(11 "B.Adhes" user "B.Adhesive")
		(13 "F.Paste" user "Package Geometry/Pastemask Top")
		(15 "B.Paste" user "Package Geometry/Pastemask Bottom")
		(5 "F.SilkS" user "Ref Des/Silkscreen Top")
		(7 "B.SilkS" user "Ref Des/Silkscreen Bottom")
		(1 "F.Mask" user "Board Geometry/Soldermask Top")
		(3 "B.Mask" user "Board Geometry/Soldermask Bottom")
		(17 "Dwgs.User" user "User.Drawings")
		(19 "Cmts.User" user "User.Comments")
		(21 "Eco1.User" user "User.Eco1")
		(23 "Eco2.User" user "User.Eco2")
		(25 "Edge.Cuts" user "Board Geometry/Outline")
		(27 "Margin" user)
		(31 "F.CrtYd" user "Package Geometry/Place Bound Top")
		(29 "B.CrtYd" user "Package Geometry/Place Bound Bottom")
		(35 "F.Fab" user "Ref Des/Assembly Top")
		(33 "B.Fab" user "Ref Des/Assembly Bottom")
	)
	(footprint ""
		(layer "B.Cu")
		(at 229.743 -75.184 90)
		(property "Reference" "R24"
			(at 0 0 90)
			(layer "B.SilkS")
			(hide yes)
			(effects
				(font
					(size 1.27 1.27)
				)
				(justify mirror)
			)
		)
		(property "Value" ""
			(at 0 0 90)
			(layer "B.Fab")
			(effects
				(font
					(size 1.27 1.27)
				)
				(justify mirror)
			)
		)
		(duplicate_pad_numbers_are_jumpers no)
		(fp_line
			(start 0.7874 -0.4064)
			(end -0.7874 -0.4064)
			(stroke
				(width 0.1524)
				(type default)
			)
			(layer "B.SilkS")
		)
		(fp_line
			(start -0.7874 -0.4064)
			(end -0.7874 0.4064)
			(stroke
				(width 0.1524)
				(type default)
			)
			(layer "B.SilkS")
		)
		(fp_line
			(start 0.7874 0.4064)
			(end 0.7874 -0.4064)
			(stroke
				(width 0.1524)
				(type default)
			)
			(layer "B.SilkS")
		)
		(fp_line
			(start -0.7874 0.4064)
			(end 0.7874 0.4064)
			(stroke
				(width 0.1524)
				(type default)
			)
			(layer "B.SilkS")
		)
		(fp_line
			(start 0.67945 -0.305054)
			(end 0.12065 -0.305054)
			(stroke
				(width 0.1)
				(type default)
			)
			(layer "B.Fab")
		)
		(fp_line
			(start 0.12065 -0.305054)
			(end 0.12065 -0.2794)
			(stroke
				(width 0.1)
				(type default)
			)
			(layer "B.Fab")
		)
		(fp_line
			(start -0.12065 -0.3048)
			(end -0.67945 -0.3048)
			(stroke
				(width 0.1)
				(type default)
			)
			(layer "B.Fab")
		)
		(fp_line
			(start -0.67945 -0.3048)
			(end -0.67945 0.3048)
			(stroke
				(width 0.1)
				(type default)
			)
			(layer "B.Fab")
		)
		(fp_line
			(start 0.12065 -0.2794)
			(end -0.12065 -0.2794)
			(stroke
				(width 0.1)
				(type default)
			)
			(layer "B.Fab")
		)
		(fp_line
			(start -0.12065 -0.2794)
			(end -0.12065 -0.3048)
			(stroke
				(width 0.1)
				(type default)
			)
			(layer "B.Fab")
		)
		(fp_line
			(start 0.12065 0.2794)
			(end 0.12065 0.3048)
			(stroke
				(width 0.1)
				(type default)
			)
			(layer "B.Fab")
		)
		(fp_line
			(start -0.120396 0.2794)
			(end 0.12065 0.2794)
			(stroke
				(width 0.1)
				(type default)
			)
			(layer "B.Fab")
		)
		(fp_line
			(start 0.67945 0.3048)
			(end 0.67945 -0.305054)
			(stroke
				(width 0.1)
				(type default)
			)
			(layer "B.Fab")
		)
		(fp_line
			(start 0.12065 0.3048)
			(end 0.67945 0.3048)
			(stroke
				(width 0.1)
				(type default)
			)
			(layer "B.Fab")
		)
		(fp_line
			(start -0.120396 0.3048)
			(end -0.120396 0.2794)
			(stroke
				(width 0.1)
				(type default)
			)
			(layer "B.Fab")
		)
		(fp_line
			(start -0.67945 0.3048)
			(end -0.120396 0.3048)
			(stroke
				(width 0.1)
				(type default)
			)
			(layer "B.Fab")
		)
		(pad "1" smd circle
			(at 0.40005 0 270)
			(size 0 0)
			(layers "B.Cu" "B.Mask" "B.Paste")
			(net "FM_U5_VCC")
		)
		(pad "2" smd circle
			(at -0.40005 0 270)
			(size 0 0)
			(layers "B.Cu" "B.Mask" "B.Paste")
			(net "P3V3_AUX")
		)
	)
	(footprint ""
		(layer "B.Cu")
		(at 266.192 -34.925 180)
		(property "Reference" "R5905"
			(at 0 0 0)
			(layer "B.SilkS")
			(hide yes)
			(effects
				(font
					(size 1.27 1.27)
				)
				(justify mirror)
			)
		)
		(property "Value" ""
			(at 0 0 0)
			(layer "B.Fab")
			(effects
				(font
					(size 1.27 1.27)
				)
				(justify mirror)
			)
		)
		(duplicate_pad_numbers_are_jumpers no)
		(fp_line
			(start 0.7874 0.4064)
			(end 0.7874 -0.4064)
			(stroke
				(width 0.1524)
				(type default)
			)
			(layer "B.SilkS")
		)
		(fp_line
			(start 0.7874 -0.4064)
			(end -0.7874 -0.4064)
			(stroke
				(width 0.1524)
				(type default)
			)
			(layer "B.SilkS")
		)
		(fp_line
			(start -0.7874 0.4064)
			(end 0.7874 0.4064)
			(stroke
				(width 0.1524)
				(type default)
			)
			(layer "B.SilkS")
		)
		(fp_line
			(start -0.7874 -0.4064)
			(end -0.7874 0.4064)
			(stroke
				(width 0.1524)
				(type default)
			)
			(layer "B.SilkS")
		)
		(fp_line
			(start 0.67945 0.3048)
			(end 0.67945 -0.305054)
			(stroke
				(width 0.1)
				(type default)
			)
			(layer "B.Fab")
		)
		(fp_line
			(start 0.67945 -0.305054)
			(end 0.12065 -0.305054)
			(stroke
				(width 0.1)
				(type default)
			)
			(layer "B.Fab")
		)
		(fp_line
			(start 0.12065 0.3048)
			(end 0.67945 0.3048)
			(stroke
				(width 0.1)
				(type default)
			)
			(layer "B.Fab")
		)
		(fp_line
			(start 0.12065 0.2794)
			(end 0.12065 0.3048)
			(stroke
				(width 0.1)
				(type default)
			)
			(layer "B.Fab")
		)
		(fp_line
			(start 0.12065 -0.2794)
			(end -0.12065 -0.2794)
			(stroke
				(width 0.1)
				(type default)
			)
			(layer "B.Fab")
		)
		(fp_line
			(start 0.12065 -0.305054)
			(end 0.12065 -0.2794)
			(stroke
				(width 0.1)
				(type default)
			)
			(layer "B.Fab")
		)
		(fp_line
			(start -0.120396 0.3048)
			(end -0.120396 0.2794)
			(stroke
				(width 0.1)
				(type default)
			)
			(layer "B.Fab")
		)
		(fp_line
			(start -0.120396 0.2794)
			(end 0.12065 0.2794)
			(stroke
				(width 0.1)
				(type default)
			)
			(layer "B.Fab")
		)
		(fp_line
			(start -0.12065 -0.2794)
			(end -0.12065 -0.3048)
			(stroke
				(width 0.1)
				(type default)
			)
			(layer "B.Fab")
		)
		(fp_line
			(start -0.12065 -0.3048)
			(end -0.67945 -0.3048)
			(stroke
				(width 0.1)
				(type default)
			)
			(layer "B.Fab")
		)
		(fp_line
			(start -0.67945 0.3048)
			(end -0.120396 0.3048)
			(stroke
				(width 0.1)
				(type default)
			)
			(layer "B.Fab")
		)
		(fp_line
			(start -0.67945 -0.3048)
			(end -0.67945 0.3048)
			(stroke
				(width 0.1)
				(type default)
			)
			(layer "B.Fab")
		)
		(pad "1" smd circle
			(at 0.40005 0)
			(size 0 0)
			(layers "B.Cu" "B.Mask" "B.Paste")
			(net "P52V_HS1_INTVCC")
		)
		(pad "2" smd circle
			(at -0.40005 0)
			(size 0 0)
			(layers "B.Cu" "B.Mask" "B.Paste")
			(net "P52V_HS1_ADR0")
		)
	)
	(footprint ""
		(layer "B.Cu")
		(at 240.538 -73.533 -90)
		(property "Reference" "C66"
			(at 0 0 90)
			(layer "B.SilkS")
			(hide yes)
			(effects
				(font
					(size 1.27 1.27)
				)
				(justify mirror)
			)
		)
		(property "Value" ""
			(at 0 0 90)
			(layer "B.Fab")
			(effects
				(font
					(size 1.27 1.27)
				)
				(justify mirror)
			)
		)
		(duplicate_pad_numbers_are_jumpers no)
		(fp_line
			(start -0.7874 0.4064)
			(end 0.7874 0.4064)
			(stroke
				(width 0.1524)
				(type default)
			)
			(layer "B.SilkS")
		)
		(fp_line
			(start 0.7874 0.4064)
			(end 0.7874 -0.4064)
			(stroke
				(width 0.1524)
				(type default)
			)
			(layer "B.SilkS")
		)
		(fp_line
			(start -0.7874 -0.4064)
			(end -0.7874 0.4064)
			(stroke
				(width 0.1524)
				(type default)
			)
			(layer "B.SilkS")
		)
		(fp_line
			(start 0.7874 -0.4064)
			(end -0.7874 -0.4064)
			(stroke
				(width 0.1524)
				(type default)
			)
			(layer "B.SilkS")
		)
		(fp_line
			(start -0.67945 0.3048)
			(end -0.120396 0.3048)
			(stroke
				(width 0.1)
				(type default)
			)
			(layer "B.Fab")
		)
		(fp_line
			(start -0.120396 0.3048)
			(end -0.120396 0.2794)
			(stroke
				(width 0.1)
				(type default)
			)
			(layer "B.Fab")
		)
		(fp_line
			(start 0.12065 0.3048)
			(end 0.67945 0.3048)
			(stroke
				(width 0.1)
				(type default)
			)
			(layer "B.Fab")
		)
		(fp_line
			(start 0.67945 0.3048)
			(end 0.67945 -0.305054)
			(stroke
				(width 0.1)
				(type default)
			)
			(layer "B.Fab")
		)
		(fp_line
			(start -0.120396 0.2794)
			(end 0.12065 0.2794)
			(stroke
				(width 0.1)
				(type default)
			)
			(layer "B.Fab")
		)
		(fp_line
			(start 0.12065 0.2794)
			(end 0.12065 0.3048)
			(stroke
				(width 0.1)
				(type default)
			)
			(layer "B.Fab")
		)
		(fp_line
			(start -0.12065 -0.2794)
			(end -0.12065 -0.3048)
			(stroke
				(width 0.1)
				(type default)
			)
			(layer "B.Fab")
		)
		(fp_line
			(start 0.12065 -0.2794)
			(end -0.12065 -0.2794)
			(stroke
				(width 0.1)
				(type default)
			)
			(layer "B.Fab")
		)
		(fp_line
			(start -0.67945 -0.3048)
			(end -0.67945 0.3048)
			(stroke
				(width 0.1)
				(type default)
			)
			(layer "B.Fab")
		)
		(fp_line
			(start -0.12065 -0.3048)
			(end -0.67945 -0.3048)
			(stroke
				(width 0.1)
				(type default)
			)
			(layer "B.Fab")
		)
		(fp_line
			(start 0.12065 -0.305054)
			(end 0.12065 -0.2794)
			(stroke
				(width 0.1)
				(type default)
			)
			(layer "B.Fab")
		)
		(fp_line
			(start 0.67945 -0.305054)
			(end 0.12065 -0.305054)
			(stroke
				(width 0.1)
				(type default)
			)
			(layer "B.Fab")
		)
		(pad "1" smd circle
			(at 0.40005 0 90)
			(size 0 0)
			(layers "B.Cu" "B.Mask" "B.Paste")
			(net "SMB_MB_PDB_R_SCL")
		)
		(pad "2" smd circle
			(at -0.40005 0 90)
			(size 0 0)
			(layers "B.Cu" "B.Mask" "B.Paste")
			(net "GND")
		)
	)
	(footprint ""
		(layer "B.Cu")
		(at 279.908 -41.91)
		(property "Reference" "PR31"
			(at 0 0 0)
			(layer "B.SilkS")
			(hide yes)
			(effects
				(font
					(size 1.27 1.27)
				)
				(justify mirror)
			)
		)
		(property "Value" ""
			(at 0 0 0)
			(layer "B.Fab")
			(effects
				(font
					(size 1.27 1.27)
				)
				(justify mirror)
			)
		)
		(duplicate_pad_numbers_are_jumpers no)
		(fp_line
			(start -0.7874 -0.4064)
			(end -0.7874 0.4064)
			(stroke
				(width 0.1524)
				(type default)
			)
			(layer "B.SilkS")
		)
		(fp_line
			(start -0.7874 0.4064)
			(end 0.7874 0.4064)
			(stroke
				(width 0.1524)
				(type default)
			)
			(layer "B.SilkS")
		)
		(fp_line
			(start 0.7874 -0.4064)
			(end -0.7874 -0.4064)
			(stroke
				(width 0.1524)
				(type default)
			)
			(layer "B.SilkS")
		)
		(fp_line
			(start 0.7874 0.4064)
			(end 0.7874 -0.4064)
			(stroke
				(width 0.1524)
				(type default)
			)
			(layer "B.SilkS")
		)
		(fp_line
			(start -0.67945 -0.3048)
			(end -0.67945 0.3048)
			(stroke
				(width 0.1)
				(type default)
			)
			(layer "B.Fab")
		)
		(fp_line
			(start -0.67945 0.3048)
			(end -0.120396 0.3048)
			(stroke
				(width 0.1)
				(type default)
			)
			(layer "B.Fab")
		)
		(fp_line
			(start -0.12065 -0.3048)
			(end -0.67945 -0.3048)
			(stroke
				(width 0.1)
				(type default)
			)
			(layer "B.Fab")
		)
		(fp_line
			(start -0.12065 -0.2794)
			(end -0.12065 -0.3048)
			(stroke
				(width 0.1)
				(type default)
			)
			(layer "B.Fab")
		)
		(fp_line
			(start -0.120396 0.2794)
			(end 0.12065 0.2794)
			(stroke
				(width 0.1)
				(type default)
			)
			(layer "B.Fab")
		)
		(fp_line
			(start -0.120396 0.3048)
			(end -0.120396 0.2794)
			(stroke
				(width 0.1)
				(type default)
			)
			(layer "B.Fab")
		)
		(fp_line
			(start 0.12065 -0.305054)
			(end 0.12065 -0.2794)
			(stroke
				(width 0.1)
				(type default)
			)
			(layer "B.Fab")
		)
		(fp_line
			(start 0.12065 -0.2794)
			(end -0.12065 -0.2794)
			(stroke
				(width 0.1)
				(type default)
			)
			(layer "B.Fab")
		)
		(fp_line
			(start 0.12065 0.2794)
			(end 0.12065 0.3048)
			(stroke
				(width 0.1)
				(type default)
			)
			(layer "B.Fab")
		)
		(fp_line
			(start 0.12065 0.3048)
			(end 0.67945 0.3048)
			(stroke
				(width 0.1)
				(type default)
			)
			(layer "B.Fab")
		)
		(fp_line
			(start 0.67945 -0.305054)
			(end 0.12065 -0.305054)
			(stroke
				(width 0.1)
				(type default)
			)
			(layer "B.Fab")
		)
		(fp_line
			(start 0.67945 0.3048)
			(end 0.67945 -0.305054)
			(stroke
				(width 0.1)
				(type default)
			)
			(layer "B.Fab")
		)
		(pad "1" smd circle
			(at 0.40005 0 180)
			(size 0 0)
			(layers "B.Cu" "B.Mask" "B.Paste")
			(net "P52V_HS1_EFAULT_R")
		)
		(pad "2" smd circle
			(at -0.40005 0 180)
			(size 0 0)
			(layers "B.Cu" "B.Mask" "B.Paste")
			(net "P52V_HS1_EFAULT")
		)
	)
	(footprint ""
		(layer "B.Cu")
		(at 222.885 -70.993 -90)
		(property "Reference" "C16"
			(at 0 0 90)
			(layer "B.SilkS")
			(hide yes)
			(effects
				(font
					(size 1.27 1.27)
				)
				(justify mirror)
			)
		)
		(property "Value" ""
			(at 0 0 90)
			(layer "B.Fab")
			(effects
				(font
					(size 1.27 1.27)
				)
				(justify mirror)
			)
		)
		(duplicate_pad_numbers_are_jumpers no)
		(fp_line
			(start -0.7874 0.4064)
			(end 0.7874 0.4064)
			(stroke
				(width 0.1524)
				(type default)
			)
			(layer "B.SilkS")
		)
		(fp_line
			(start 0.7874 0.4064)
			(end 0.7874 -0.4064)
			(stroke
				(width 0.1524)
				(type default)
			)
			(layer "B.SilkS")
		)
		(fp_line
			(start -0.7874 -0.4064)
			(end -0.7874 0.4064)
			(stroke
				(width 0.1524)
				(type default)
			)
			(layer "B.SilkS")
		)
		(fp_line
			(start 0.7874 -0.4064)
			(end -0.7874 -0.4064)
			(stroke
				(width 0.1524)
				(type default)
			)
			(layer "B.SilkS")
		)
		(fp_line
			(start -0.67945 0.3048)
			(end -0.120396 0.3048)
			(stroke
				(width 0.1)
				(type default)
			)
			(layer "B.Fab")
		)
		(fp_line
			(start -0.120396 0.3048)
			(end -0.120396 0.2794)
			(stroke
				(width 0.1)
				(type default)
			)
			(layer "B.Fab")
		)
		(fp_line
			(start 0.12065 0.3048)
			(end 0.67945 0.3048)
			(stroke
				(width 0.1)
				(type default)
			)
			(layer "B.Fab")
		)
		(fp_line
			(start 0.67945 0.3048)
			(end 0.67945 -0.305054)
			(stroke
				(width 0.1)
				(type default)
			)
			(layer "B.Fab")
		)
		(fp_line
			(start -0.120396 0.2794)
			(end 0.12065 0.2794)
			(stroke
				(width 0.1)
				(type default)
			)
			(layer "B.Fab")
		)
		(fp_line
			(start 0.12065 0.2794)
			(end 0.12065 0.3048)
			(stroke
				(width 0.1)
				(type default)
			)
			(layer "B.Fab")
		)
		(fp_line
			(start -0.12065 -0.2794)
			(end -0.12065 -0.3048)
			(stroke
				(width 0.1)
				(type default)
			)
			(layer "B.Fab")
		)
		(fp_line
			(start 0.12065 -0.2794)
			(end -0.12065 -0.2794)
			(stroke
				(width 0.1)
				(type default)
			)
			(layer "B.Fab")
		)
		(fp_line
			(start -0.67945 -0.3048)
			(end -0.67945 0.3048)
			(stroke
				(width 0.1)
				(type default)
			)
			(layer "B.Fab")
		)
		(fp_line
			(start -0.12065 -0.3048)
			(end -0.67945 -0.3048)
			(stroke
				(width 0.1)
				(type default)
			)
			(layer "B.Fab")
		)
		(fp_line
			(start 0.12065 -0.305054)
			(end 0.12065 -0.2794)
			(stroke
				(width 0.1)
				(type default)
			)
			(layer "B.Fab")
		)
		(fp_line
			(start 0.67945 -0.305054)
			(end 0.12065 -0.305054)
			(stroke
				(width 0.1)
				(type default)
			)
			(layer "B.Fab")
		)
		(pad "1" smd circle
			(at 0.40005 0 90)
			(size 0 0)
			(layers "B.Cu" "B.Mask" "B.Paste")
			(net "PWRGD_GPU_HSC_BUF_R")
		)
		(pad "2" smd circle
			(at -0.40005 0 90)
			(size 0 0)
			(layers "B.Cu" "B.Mask" "B.Paste")
			(net "GND")
		)
	)
	(footprint ""
		(layer "B.Cu")
		(at 186.309 -83.439)
		(property "Reference" "R5879"
			(at 0 0 0)
			(layer "B.SilkS")
			(hide yes)
			(effects
				(font
					(size 1.27 1.27)
				)
				(justify mirror)
			)
		)
		(property "Value" ""
			(at 0 0 0)
			(layer "B.Fab")
			(effects
				(font
					(size 1.27 1.27)
				)
				(justify mirror)
			)
		)
		(duplicate_pad_numbers_are_jumpers no)
		(fp_line
			(start -0.7874 -0.4064)
			(end -0.7874 0.4064)
			(stroke
				(width 0.1524)
				(type default)
			)
			(layer "B.SilkS")
		)
		(fp_line
			(start -0.7874 0.4064)
			(end 0.7874 0.4064)
			(stroke
				(width 0.1524)
				(type default)
			)
			(layer "B.SilkS")
		)
		(fp_line
			(start 0.7874 -0.4064)
			(end -0.7874 -0.4064)
			(stroke
				(width 0.1524)
				(type default)
			)
			(layer "B.SilkS")
		)
		(fp_line
			(start 0.7874 0.4064)
			(end 0.7874 -0.4064)
			(stroke
				(width 0.1524)
				(type default)
			)
			(layer "B.SilkS")
		)
		(fp_line
			(start -0.67945 -0.3048)
			(end -0.67945 0.3048)
			(stroke
				(width 0.1)
				(type default)
			)
			(layer "B.Fab")
		)
		(fp_line
			(start -0.67945 0.3048)
			(end -0.120396 0.3048)
			(stroke
				(width 0.1)
				(type default)
			)
			(layer "B.Fab")
		)
		(fp_line
			(start -0.12065 -0.3048)
			(end -0.67945 -0.3048)
			(stroke
				(width 0.1)
				(type default)
			)
			(layer "B.Fab")
		)
		(fp_line
			(start -0.12065 -0.2794)
			(end -0.12065 -0.3048)
			(stroke
				(width 0.1)
				(type default)
			)
			(layer "B.Fab")
		)
		(fp_line
			(start -0.120396 0.2794)
			(end 0.12065 0.2794)
			(stroke
				(width 0.1)
				(type default)
			)
			(layer "B.Fab")
		)
		(fp_line
			(start -0.120396 0.3048)
			(end -0.120396 0.2794)
			(stroke
				(width 0.1)
				(type default)
			)
			(layer "B.Fab")
		)
		(fp_line
			(start 0.12065 -0.305054)
			(end 0.12065 -0.2794)
			(stroke
				(width 0.1)
				(type default)
			)
			(layer "B.Fab")
		)
		(fp_line
			(start 0.12065 -0.2794)
			(end -0.12065 -0.2794)
			(stroke
				(width 0.1)
				(type default)
			)
			(layer "B.Fab")
		)
		(fp_line
			(start 0.12065 0.2794)
			(end 0.12065 0.3048)
			(stroke
				(width 0.1)
				(type default)
			)
			(layer "B.Fab")
		)
		(fp_line
			(start 0.12065 0.3048)
			(end 0.67945 0.3048)
			(stroke
				(width 0.1)
				(type default)
			)
			(layer "B.Fab")
		)
		(fp_line
			(start 0.67945 -0.305054)
			(end 0.12065 -0.305054)
			(stroke
				(width 0.1)
				(type default)
			)
			(layer "B.Fab")
		)
		(fp_line
			(start 0.67945 0.3048)
			(end 0.67945 -0.305054)
			(stroke
				(width 0.1)
				(type default)
			)
			(layer "B.Fab")
		)
		(pad "1" smd circle
			(at 0.40005 0 180)
			(size 0 0)
			(layers "B.Cu" "B.Mask" "B.Paste")
			(net "SMB_P52V_VPDB_SDA")
		)
		(pad "2" smd circle
			(at -0.40005 0 180)
			(size 0 0)
			(layers "B.Cu" "B.Mask" "B.Paste")
			(net "SMB_P52V_HSC_SDA")
		)
	)
)
